# BASEBOARD_FAB2 (Tioga Pass) — schematic netlist excerpt (pin names and nets, part order shuffled) for the footprints in the layout excerpt that follows; sources: Cadence DE-HDL packaged netlist, KiCad conversion of Wiwynn_Tioga_Pass_MB.brd

J1G1  SCONN288_H44441004  SCONN  pkg PIP  page 77
  \12v\(1)  = P12V_NVDIMM_GHJ
  VSS(93)  = GND
  DQ(4)  = M_G_DQ<5>
  VSS(92)  = GND
  DQ(0)  = M_G_DQ<1>
  VSS(91)  = GND
  DQS9P  = M_G_DQS_DP<9>
  DQS9N  = M_G_DQS_DN<9>
  VSS(90)  = GND
  DQ(6)  = M_G_DQ<7>
  VSS(89)  = GND
  DQ(2)  = M_G_DQ<3>
  VSS(88)  = GND
  DQ(12)  = M_G_DQ<13>
  VSS(87)  = GND
  DQ(8)  = M_G_DQ<9>
  VSS(86)  = GND
  DQS10P  = M_G_DQS_DP<10>
  DQS10N  = M_G_DQS_DN<10>
  VSS(85)  = GND
  DQ(14)  = M_G_DQ<15>
  VSS(84)  = GND
  DQ(10)  = M_G_DQ<11>
  VSS(83)  = GND
  DQ(20)  = M_G_DQ<21>
  VSS(82)  = GND
  DQ(16)  = M_G_DQ<17>
  VSS(81)  = GND
  DQS11P  = M_G_DQS_DP<11>
  DQS11N  = M_G_DQS_DN<11>
  VSS(80)  = GND
  DQ(22)  = M_G_DQ<23>
  VSS(79)  = GND
  DQ(18)  = M_G_DQ<19>
  VSS(78)  = GND
  DQ(28)  = M_G_DQ<29>
  VSS(77)  = GND
  DQ(24)  = M_G_DQ<25>
  VSS(76)  = GND
  DQS12P  = M_G_DQS_DP<12>
  DQS12N  = M_G_DQS_DN<12>
  VSS(75)  = GND
  DQ(30)  = M_G_DQ<31>
  VSS(74)  = GND
  DQ(26)  = M_G_DQ<27>
  VSS(73)  = GND
  CB(4)  = M_G_ECC<5>
  VSS(72)  = GND
  CB(0)  = M_G_ECC<1>
  VSS(71)  = GND
  DQS17P  = M_G_DQS_DP<17>
  DQS17N  = M_G_DQS_DN<17>
  VSS(70)  = GND
  CB(6)  = M_G_ECC<7>
  VSS(69)  = GND
  CB(2)  = M_G_ECC<3>
  VSS(68)  = GND
  RESET_N  = M_GHJ_RST_N
  VDD(25)  = PVDDQ_GHJ
  CKE(0)  = M_G_CKE<0>
  VDD(24)  = PVDDQ_GHJ
  ACT_N  = M_G_ACT_N
  BG(0)  = M_G_BG<0>
  VDD(23)  = PVDDQ_GHJ
  A12  = M_G_MA<12>
  A9  = M_G_MA<9>
  VDD(22)  = PVDDQ_GHJ
  A8  = M_G_MA<8>
  A6  = M_G_MA<6>
  VDD(21)  = PVDDQ_GHJ
  A3  = M_G_MA<3>
  A1  = M_G_MA<1>
  VDD(20)  = PVDDQ_GHJ
  CK0P  = M_G_CLK_DP<0>
  CK0N  = M_G_CLK_DN<0>
  VDD(19)  = PVDDQ_GHJ
  VTT(1)  = PVTT_GHJ
  EVENT_N  = FM_DIMM_EVENT_COD_N
  A0  = M_G_MA<0>
  VDD(18)  = PVDDQ_GHJ
  BA(0)  = M_G_BA<0>
  A16_RAS_N  = M_G_MA<16>
  VDD(17)  = PVDDQ_GHJ
  S0_N  = M_G_CS_N<0>
  VDD(16)  = PVDDQ_GHJ
  A15_CAS_N  = M_G_MA<15>
  ODT(0)  = M_G_ODT<0>
  VDD(15)  = PVDDQ_GHJ
  S1_N  = M_G_CS_N<1>
  VDD(14)  = PVDDQ_GHJ
  ODT(1)  = M_G_ODT<1>
  VDD(13)  = PVDDQ_GHJ
  S2_N_C(0)  = M_G_CS_N<2>
  VSS(67)  = GND
  DQ(36)  = M_G_DQ<37>
  VSS(66)  = GND
  DQ(32)  = M_G_DQ<33>
  VSS(65)  = GND
  DQS13P  = M_G_DQS_DP<13>
  DQS13N  = M_G_DQS_DN<13>
  VSS(64)  = GND
  DQ(38)  = M_G_DQ<39>
  VSS(63)  = GND
  DQ(34)  = M_G_DQ<35>
  VSS(62)  = GND
  DQ(44)  = M_G_DQ<45>
  VSS(61)  = GND
  DQ(40)  = M_G_DQ<41>
  VSS(60)  = GND
  DQS14P  = M_G_DQS_DP<14>
  DQS14N  = M_G_DQS_DN<14>
  VSS(59)  = GND
  DQ(46)  = M_G_DQ<47>
  VSS(58)  = GND
  DQ(42)  = M_G_DQ<43>
  VSS(57)  = GND
  DQ(52)  = M_G_DQ<53>
  VSS(56)  = GND
  DQ(48)  = M_G_DQ<49>
  VSS(55)  = GND
  DQS15P  = M_G_DQS_DP<15>
  DQS15N  = M_G_DQS_DN<15>
  VSS(54)  = GND
  DQ(54)  = M_G_DQ<55>
  VSS(53)  = GND
  DQ(50)  = M_G_DQ<51>
  VSS(52)  = GND
  DQ(60)  = M_G_DQ<61>
  VSS(51)  = GND
  DQ(56)  = M_G_DQ<57>
  VSS(50)  = GND
  DQS16P  = M_G_DQS_DP<16>
  DQS16N  = M_G_DQS_DN<16>
  VSS(49)  = GND
  DQ(62)  = M_G_DQ<63>
  VSS(48)  = GND
  DQ(58)  = M_G_DQ<59>
  VSS(47)  = GND
  SA(0)  = GND
  SA(1)  = GND
  SCL  = SMB_DDR_GHJ_VPP_SCL
  VPP(4)  = PVPP_GHJ
  VPP(3)  = PVPP_GHJ
  RFU(2)  = TP_CH_G_DIMM_G0_RFU_2
  \12v\(0)  = P12V_NVDIMM_GHJ
  VREFCA  = M_G_VREF
  VSS(46)  = GND
  DQ(5)  = M_G_DQ<4>
  VSS(45)  = GND
  DQ(1)  = M_G_DQ<0>
  VSS(44)  = GND
  DQS0N  = M_G_DQS_DN<0>
  DQS0P  = M_G_DQS_DP<0>
  VSS(43)  = GND
  DQ(7)  = M_G_DQ<6>
  VSS(42)  = GND
  DQ(3)  = M_G_DQ<2>
  VSS(41)  = GND
  DQ(13)  = M_G_DQ<12>
  VSS(40)  = GND
  DQ(9)  = M_G_DQ<8>
  VSS(39)  = GND
  DQS1N  = M_G_DQS_DN<1>
  DQS1P  = M_G_DQS_DP<1>
  VSS(38)  = GND
  DQ(15)  = M_G_DQ<14>
  VSS(37)  = GND
  DQ(11)  = M_G_DQ<10>
  VSS(36)  = GND
  DQ(21)  = M_G_DQ<20>
  VSS(35)  = GND
  DQ(17)  = M_G_DQ<16>
  VSS(34)  = GND
  DQS2N  = M_G_DQS_DN<2>
  DQS2P  = M_G_DQS_DP<2>
  VSS(33)  = GND
  DQ(23)  = M_G_DQ<22>
  VSS(32)  = GND
  DQ(19)  = M_G_DQ<18>
  VSS(31)  = GND
  DQ(29)  = M_G_DQ<28>
  VSS(30)  = GND
  DQ(25)  = M_G_DQ<24>
  VSS(29)  = GND
  DQS3N  = M_G_DQS_DN<3>
  DQS3P  = M_G_DQS_DP<3>
  VSS(28)  = GND
  DQ(31)  = M_G_DQ<30>
  VSS(27)  = GND
  DQ(27)  = M_G_DQ<26>
  VSS(26)  = GND
  CB(5)  = M_G_ECC<4>
  VSS(25)  = GND
  CB(1)  = M_G_ECC<0>
  VSS(24)  = GND
  DQS8N  = M_G_DQS_DN<8>
  DQS8P  = M_G_DQS_DP<8>
  VSS(23)  = GND
  CB(7)  = M_G_ECC<6>
  VSS(22)  = GND
  CB(3)  = M_G_ECC<2>
  VSS(21)  = GND
  CKE(1)  = M_G_CKE<1>
  VDD(12)  = PVDDQ_GHJ
  RFU(0)  = TP_CH_G_DIMM_G0_RFU_0
  VDD(11)  = PVDDQ_GHJ
  BG(1)  = M_G_BG<1>
  ALERT_N  = M_G_ALERT_N
  VDD(10)  = PVDDQ_GHJ
  A11  = M_G_MA<11>
  A7  = M_G_MA<7>
  VDD(9)  = PVDDQ_GHJ
  A5  = M_G_MA<5>
  A4  = M_G_MA<4>
  VDD(8)  = PVDDQ_GHJ
  A2  = M_G_MA<2>
  VDD(7)  = PVDDQ_GHJ
  CK1P  = M_G_CLK_DP<1>
  CK1N  = M_G_CLK_DN<1>
  VDD(6)  = PVDDQ_GHJ
  VTT(0)  = PVTT_GHJ
  PAR  = M_G_PAR
  VDD(5)  = PVDDQ_GHJ
  BA(1)  = M_G_BA<1>
  A10  = M_G_MA<10>
  VDD(4)  = PVDDQ_GHJ
  RFU(1)  = TP_CH_G_DIMM_G0_RFU_1
  A14_WE_N  = M_G_MA<14>
  VDD(3)  = PVDDQ_GHJ
  SAVE_N_NC  = FM_ADR_COMPLETE_GHJ_N
  VDD(2)  = PVDDQ_GHJ
  A13  = M_G_MA<13>
  VDD(1)  = PVDDQ_GHJ
  A17  = M_G_MA<17>
  C(2)  = M_G_C<2>
  VDD(0)  = PVDDQ_GHJ
  S3_N_C(1)  = M_G_CS_N<3>
  SA(2)  = GND
  VSS(20)  = GND
  DQ(37)  = M_G_DQ<36>
  VSS(19)  = GND
  DQ(33)  = M_G_DQ<32>
  VSS(18)  = GND
  DQS4N  = M_G_DQS_DN<4>
  DQS4P  = M_G_DQS_DP<4>
  VSS(17)  = GND
  DQ(39)  = M_G_DQ<38>
  VSS(16)  = GND
  DQ(35)  = M_G_DQ<34>
  VSS(15)  = GND
  DQ(45)  = M_G_DQ<44>
  VSS(14)  = GND
  DQ(41)  = M_G_DQ<40>
  VSS(13)  = GND
  DQS5N  = M_G_DQS_DN<5>
  DQS5P  = M_G_DQS_DP<5>
  VSS(12)  = GND
  DQ(47)  = M_G_DQ<46>
  VSS(11)  = GND
  DQ(43)  = M_G_DQ<42>
  VSS(10)  = GND
  DQ(53)  = M_G_DQ<52>
  VSS(9)  = GND
  DQ(49)  = M_G_DQ<48>
  VSS(8)  = GND
  DQS6N  = M_G_DQS_DN<6>
  DQS6P  = M_G_DQS_DP<6>
  VSS(7)  = GND
  DQ(55)  = M_G_DQ<54>
  VSS(6)  = GND
  DQ(51)  = M_G_DQ<50>
  VSS(5)  = GND
  DQ(61)  = M_G_DQ<60>
  VSS(4)  = GND
  DQ(57)  = M_G_DQ<56>
  VSS(3)  = GND
  DQS7N  = M_G_DQS_DN<7>
  DQS7P  = M_G_DQS_DP<7>
  VSS(2)  = GND
  DQ(63)  = M_G_DQ<62>
  VSS(1)  = GND
  DQ(59)  = M_G_DQ<58>
  VSS(0)  = GND
  VDDSPD  = PVPP_GHJ
  SDA  = SMB_DDR_GHJ_VPP_SDA
  VPP(1)  = PVPP_GHJ
  VPP(0)  = PVPP_GHJ
  VPP(2)  = PVPP_GHJ

(kicad_pcb
	(version 20260206)
	(generator "pcbnew")
	(generator_version "10.0")
	(general
		(thickness 1.6)
		(legacy_teardrops no)
	)
	(paper "A4")
	(title_block
		(title "Wiwynn_Tioga_Pass_MB.brd")
		(comment 1 "Tioga Pass / footprint 2018 of 4770 (J1G1), pads 152-201 of 291")
	)
	(layers
		(0 "F.Cu" signal "TOP")
		(4 "In1.Cu" signal "L2GND")
		(6 "In2.Cu" signal "L3")
		(8 "In3.Cu" signal "L4GND")
		(10 "In4.Cu" signal "L5")
		(12 "In5.Cu" signal "L6GND")
		(14 "In6.Cu" signal "L7VCC")
		(16 "In7.Cu" signal "L8VCC")
		(18 "In8.Cu" signal "L9GND")
		(20 "In9.Cu" signal "L10")
		(22 "In10.Cu" signal "L11GND")
		(24 "In11.Cu" signal "L12")
		(26 "In12.Cu" signal "L13GND")
		(2 "B.Cu" signal "BOTTOM")
		(9 "F.Adhes" user "F.Adhesive")
		(11 "B.Adhes" user "B.Adhesive")
		(13 "F.Paste" user "Package Geometry/Pastemask Top")
		(15 "B.Paste" user "Package Geometry/Pastemask Bottom")
		(5 "F.SilkS" user "Ref Des/Silkscreen Top")
		(7 "B.SilkS" user "Ref Des/Silkscreen Bottom")
		(1 "F.Mask" user "Board Geometry/Soldermask Top")
		(3 "B.Mask" user "Board Geometry/Soldermask Bottom")
		(17 "Dwgs.User" user "User.Drawings")
		(19 "Cmts.User" user "User.Comments")
		(21 "Eco1.User" user "User.Eco1")
		(23 "Eco2.User" user "User.Eco2")
		(25 "Edge.Cuts" user "Board Geometry/Outline")
		(27 "Margin" user)
		(31 "F.CrtYd" user "Package Geometry/Place Bound Top")
		(29 "B.CrtYd" user "Package Geometry/Place Bound Bottom")
		(35 "F.Fab" user "Ref Des/Assembly Top")
		(33 "B.Fab" user "Ref Des/Assembly Bottom")
	)
	(footprint ""
		(layer "F.Cu")
		(at 29.699458 -15.423642 90)
		(property "Reference" "J1G1"
			(at 9.314688 35.070542 0)
			(unlocked yes)
			(layer "F.SilkS")
			(effects
				(font
					(size 0.7874 0.5842)
					(thickness 0.1524)
				)
				(justify left)
			)
		)
		(property "Value" ""
			(at 0 0 90)
			(layer "F.Fab")
			(effects
				(font
					(size 1.27 1.27)
				)
			)
		)
		(duplicate_pad_numbers_are_jumpers no)
		(pad "149" smd rect
			(at 4.59994 3.400044 90)
			(size 1.8034 0.508)
			(layers "F.Cu" "F.Mask" "F.Paste")
			(net "GND")
		)
		(pad "150" smd rect
			(at 4.59994 4.249928 90)
			(size 1.8034 0.508)
			(layers "F.Cu" "F.Mask" "F.Paste")
			(net "M_G_DQ<0>")
		)
		(pad "151" smd rect
			(at 4.59994 5.100066 90)
			(size 1.8034 0.508)
			(layers "F.Cu" "F.Mask" "F.Paste")
			(net "GND")
		)
		(pad "152" smd rect
			(at 4.59994 5.94995 90)
			(size 1.8034 0.508)
			(layers "F.Cu" "F.Mask" "F.Paste")
			(net "M_G_DQS_DN<0>")
		)
		(pad "153" smd rect
			(at 4.59994 6.800088 90)
			(size 1.8034 0.508)
			(layers "F.Cu" "F.Mask" "F.Paste")
			(net "M_G_DQS_DP<0>")
		)
		(pad "154" smd rect
			(at 4.59994 7.649972 90)
			(size 1.8034 0.508)
			(layers "F.Cu" "F.Mask" "F.Paste")
			(net "GND")
		)
		(pad "155" smd rect
			(at 4.59994 8.50011 90)
			(size 1.8034 0.508)
			(layers "F.Cu" "F.Mask" "F.Paste")
			(net "M_G_DQ<6>")
		)
		(pad "156" smd rect
			(at 4.59994 9.349994 90)
			(size 1.8034 0.508)
			(layers "F.Cu" "F.Mask" "F.Paste")
			(net "GND")
		)
		(pad "157" smd rect
			(at 4.59994 10.199878 90)
			(size 1.8034 0.508)
			(layers "F.Cu" "F.Mask" "F.Paste")
			(net "M_G_DQ<2>")
		)
		(pad "158" smd rect
			(at 4.59994 11.050016 90)
			(size 1.8034 0.508)
			(layers "F.Cu" "F.Mask" "F.Paste")
			(net "GND")
		)
		(pad "159" smd rect
			(at 4.59994 11.8999 90)
			(size 1.8034 0.508)
			(layers "F.Cu" "F.Mask" "F.Paste")
			(net "M_G_DQ<12>")
		)
		(pad "160" smd rect
			(at 4.59994 12.750038 90)
			(size 1.8034 0.508)
			(layers "F.Cu" "F.Mask" "F.Paste")
			(net "GND")
		)
		(pad "161" smd rect
			(at 4.59994 13.599922 90)
			(size 1.8034 0.508)
			(layers "F.Cu" "F.Mask" "F.Paste")
			(net "M_G_DQ<8>")
		)
		(pad "162" smd rect
			(at 4.59994 14.45006 90)
			(size 1.8034 0.508)
			(layers "F.Cu" "F.Mask" "F.Paste")
			(net "GND")
		)
		(pad "163" smd rect
			(at 4.59994 15.299944 90)
			(size 1.8034 0.508)
			(layers "F.Cu" "F.Mask" "F.Paste")
			(net "M_G_DQS_DN<1>")
		)
		(pad "164" smd rect
			(at 4.59994 16.150082 90)
			(size 1.8034 0.508)
			(layers "F.Cu" "F.Mask" "F.Paste")
			(net "M_G_DQS_DP<1>")
		)
		(pad "165" smd rect
			(at 4.59994 16.999966 90)
			(size 1.8034 0.508)
			(layers "F.Cu" "F.Mask" "F.Paste")
			(net "GND")
		)
		(pad "166" smd rect
			(at 4.59994 17.850104 90)
			(size 1.8034 0.508)
			(layers "F.Cu" "F.Mask" "F.Paste")
			(net "M_G_DQ<14>")
		)
		(pad "167" smd rect
			(at 4.59994 18.699988 90)
			(size 1.8034 0.508)
			(layers "F.Cu" "F.Mask" "F.Paste")
			(net "GND")
		)
		(pad "168" smd rect
			(at 4.59994 19.550126 90)
			(size 1.8034 0.508)
			(layers "F.Cu" "F.Mask" "F.Paste")
			(net "M_G_DQ<10>")
		)
		(pad "169" smd rect
			(at 4.59994 20.40001 90)
			(size 1.8034 0.508)
			(layers "F.Cu" "F.Mask" "F.Paste")
			(net "GND")
		)
		(pad "170" smd rect
			(at 4.59994 21.249894 90)
			(size 1.8034 0.508)
			(layers "F.Cu" "F.Mask" "F.Paste")
			(net "M_G_DQ<20>")
		)
		(pad "171" smd rect
			(at 4.59994 22.100032 90)
			(size 1.8034 0.508)
			(layers "F.Cu" "F.Mask" "F.Paste")
			(net "GND")
		)
		(pad "172" smd rect
			(at 4.59994 22.949916 90)
			(size 1.8034 0.508)
			(layers "F.Cu" "F.Mask" "F.Paste")
			(net "M_G_DQ<16>")
		)
		(pad "173" smd rect
			(at 4.59994 23.800054 90)
			(size 1.8034 0.508)
			(layers "F.Cu" "F.Mask" "F.Paste")
			(net "GND")
		)
		(pad "174" smd rect
			(at 4.59994 24.649938 90)
			(size 1.8034 0.508)
			(layers "F.Cu" "F.Mask" "F.Paste")
			(net "M_G_DQS_DN<2>")
		)
		(pad "175" smd rect
			(at 4.59994 25.500076 90)
			(size 1.8034 0.508)
			(layers "F.Cu" "F.Mask" "F.Paste")
			(net "M_G_DQS_DP<2>")
		)
		(pad "176" smd rect
			(at 4.59994 26.34996 90)
			(size 1.8034 0.508)
			(layers "F.Cu" "F.Mask" "F.Paste")
			(net "GND")
		)
		(pad "177" smd rect
			(at 4.59994 27.200098 90)
			(size 1.8034 0.508)
			(layers "F.Cu" "F.Mask" "F.Paste")
			(net "M_G_DQ<22>")
		)
		(pad "178" smd rect
			(at 4.59994 28.049982 90)
			(size 1.8034 0.508)
			(layers "F.Cu" "F.Mask" "F.Paste")
			(net "GND")
		)
		(pad "179" smd rect
			(at 4.59994 28.90012 90)
			(size 1.8034 0.508)
			(layers "F.Cu" "F.Mask" "F.Paste")
			(net "M_G_DQ<18>")
		)
		(pad "180" smd rect
			(at 4.59994 29.750004 90)
			(size 1.8034 0.508)
			(layers "F.Cu" "F.Mask" "F.Paste")
			(net "GND")
		)
		(pad "181" smd rect
			(at 4.59994 30.599888 90)
			(size 1.8034 0.508)
			(layers "F.Cu" "F.Mask" "F.Paste")
			(net "M_G_DQ<28>")
		)
		(pad "182" smd rect
			(at 4.59994 31.450026 90)
			(size 1.8034 0.508)
			(layers "F.Cu" "F.Mask" "F.Paste")
			(net "GND")
		)
		(pad "183" smd rect
			(at 4.59994 32.29991 90)
			(size 1.8034 0.508)
			(layers "F.Cu" "F.Mask" "F.Paste")
			(net "M_G_DQ<24>")
		)
		(pad "184" smd rect
			(at 4.59994 33.150048 90)
			(size 1.8034 0.508)
			(layers "F.Cu" "F.Mask" "F.Paste")
			(net "GND")
		)
		(pad "185" smd rect
			(at 4.59994 33.999932 90)
			(size 1.8034 0.508)
			(layers "F.Cu" "F.Mask" "F.Paste")
			(net "M_G_DQS_DN<3>")
		)
		(pad "186" smd rect
			(at 4.59994 34.85007 90)
			(size 1.8034 0.508)
			(layers "F.Cu" "F.Mask" "F.Paste")
			(net "M_G_DQS_DP<3>")
		)
		(pad "187" smd rect
			(at 4.59994 35.699954 90)
			(size 1.8034 0.508)
			(layers "F.Cu" "F.Mask" "F.Paste")
			(net "GND")
		)
		(pad "188" smd rect
			(at 4.59994 36.550092 90)
			(size 1.8034 0.508)
			(layers "F.Cu" "F.Mask" "F.Paste")
			(net "M_G_DQ<30>")
		)
		(pad "189" smd rect
			(at 4.59994 37.399976 90)
			(size 1.8034 0.508)
			(layers "F.Cu" "F.Mask" "F.Paste")
			(net "GND")
		)
		(pad "190" smd rect
			(at 4.59994 38.250114 90)
			(size 1.8034 0.508)
			(layers "F.Cu" "F.Mask" "F.Paste")
			(net "M_G_DQ<26>")
		)
		(pad "191" smd rect
			(at 4.59994 39.099998 90)
			(size 1.8034 0.508)
			(layers "F.Cu" "F.Mask" "F.Paste")
			(net "GND")
		)
		(pad "192" smd rect
			(at 4.59994 39.949882 90)
			(size 1.8034 0.508)
			(layers "F.Cu" "F.Mask" "F.Paste")
			(net "M_G_ECC<4>")
		)
		(pad "193" smd rect
			(at 4.59994 40.80002 90)
			(size 1.8034 0.508)
			(layers "F.Cu" "F.Mask" "F.Paste")
			(net "GND")
		)
		(pad "194" smd rect
			(at 4.59994 41.649904 90)
			(size 1.8034 0.508)
			(layers "F.Cu" "F.Mask" "F.Paste")
			(net "M_G_ECC<0>")
		)
		(pad "195" smd rect
			(at 4.59994 42.500042 90)
			(size 1.8034 0.508)
			(layers "F.Cu" "F.Mask" "F.Paste")
			(net "GND")
		)
		(pad "196" smd rect
			(at 4.59994 43.349926 90)
			(size 1.8034 0.508)
			(layers "F.Cu" "F.Mask" "F.Paste")
			(net "M_G_DQS_DN<8>")
		)
		(pad "197" smd rect
			(at 4.59994 44.200064 90)
			(size 1.8034 0.508)
			(layers "F.Cu" "F.Mask" "F.Paste")
			(net "M_G_DQS_DP<8>")
		)
		(pad "198" smd rect
			(at 4.59994 45.049948 90)
			(size 1.8034 0.508)
			(layers "F.Cu" "F.Mask" "F.Paste")
			(net "GND")
		)
	)
)
